(kicad_pcb
	(version 20260206)
	(generator "pcbnew")
	(generator_version "10.0")
	(general
		(thickness 1.6)
		(legacy_teardrops no)
	)
	(paper "A4")
	(title_block
		(title "peb — Lightning_PEB_BRD.brd")
		(comment 1 "Lightning (Wiwynn / Facebook NVMe JBOF) / footprints 1927-1934 of 2563")
	)
	(layers
		(0 "F.Cu" signal "TOP")
		(4 "In1.Cu" signal "L2GND")
		(6 "In2.Cu" signal "L3")
		(8 "In3.Cu" signal "L4VCC")
		(10 "In4.Cu" signal "L5VCC")
		(12 "In5.Cu" signal "L6")
		(14 "In6.Cu" signal "L7GND")
		(2 "B.Cu" signal "BOTTOM")
		(9 "F.Adhes" user "F.Adhesive")
		(11 "B.Adhes" user "B.Adhesive")
		(13 "F.Paste" user "Package Geometry/Pastemask Top")
		(15 "B.Paste" user "Package Geometry/Pastemask Bottom")
		(5 "F.SilkS" user "Ref Des/Silkscreen Top")
		(7 "B.SilkS" user "Ref Des/Silkscreen Bottom")
		(1 "F.Mask" user "Board Geometry/Soldermask Top")
		(3 "B.Mask" user "Board Geometry/Soldermask Bottom")
		(17 "Dwgs.User" user "User.Drawings")
		(19 "Cmts.User" user "User.Comments")
		(21 "Eco1.User" user "User.Eco1")
		(23 "Eco2.User" user "User.Eco2")
		(25 "Edge.Cuts" user "Board Geometry/Outline")
		(27 "Margin" user)
		(31 "F.CrtYd" user "Package Geometry/Place Bound Top")
		(29 "B.CrtYd" user "Package Geometry/Place Bound Bottom")
		(35 "F.Fab" user "Ref Des/Assembly Top")
		(33 "B.Fab" user "Ref Des/Assembly Bottom")
	)
	(footprint ""
		(layer "B.Cu")
		(at 20.955 -127.635 90)
		(property "Reference" "R344"
			(at 0 0 90)
			(layer "B.SilkS")
			(hide yes)
			(effects
				(font
					(size 1.27 1.27)
				)
				(justify mirror)
			)
		)
		(property "Value" "3K3R2F-2-GP"
			(at -0.064008 -3.993896 90)
			(unlocked yes)
			(layer "B.Fab")
			(hide yes)
			(effects
				(font
					(size 1.016 1.016)
					(thickness 0.1524)
				)
				(justify mirror)
			)
		)
		(property "Device Type" "R402H16"
			(at -0.064008 -5.517896 90)
			(unlocked yes)
			(layer "B.Fab")
			(hide yes)
			(effects
				(font
					(size 1.016 1.016)
					(thickness 0.1524)
				)
				(justify mirror)
			)
		)
		(duplicate_pad_numbers_are_jumpers no)
		(fp_line
			(start 0.508 -0.9398)
			(end 0.508 0.9398)
			(stroke
				(width 0.1524)
				(type default)
			)
			(layer "B.SilkS")
		)
		(fp_line
			(start -0.508 -0.9398)
			(end 0.508 -0.9398)
			(stroke
				(width 0.1524)
				(type default)
			)
			(layer "B.SilkS")
		)
		(fp_rect
			(start 0.508 0.9398)
			(end -0.508 -0.9398)
			(stroke
				(width 0)
				(type default)
			)
			(fill no)
			(layer "B.CrtYd")
		)
		(fp_rect
			(start 0.508 0.9398)
			(end -0.508 -0.9398)
			(stroke
				(width 0)
				(type default)
			)
			(fill no)
			(layer "B.Fab")
		)
		(pad "1" smd custom
			(at 0 -0.4445 270)
			(size 0.1397 0.1397)
			(layers "B.Cu" "B.Mask" "B.Paste")
			(net "P3V3_STBY")
			(options
				(clearance outline)
				(anchor circle)
			)
			(primitives
				(gr_poly
					(pts
						(arc
							(start -0.1778 0.2794)
							(mid -0.249642 0.249642)
							(end -0.2794 0.1778)
						)
						(arc
							(start -0.2794 -0.1778)
							(mid -0.249642 -0.249642)
							(end -0.1778 -0.2794)
						)
						(arc
							(start 0.1778 -0.2794)
							(mid 0.249642 -0.249642)
							(end 0.2794 -0.1778)
						)
						(arc
							(start 0.2794 0.1778)
							(mid 0.249642 0.249642)
							(end 0.1778 0.2794)
						)
					)
					(width 0)
					(fill yes)
				)
			)
		)
		(pad "2" smd custom
			(at 0 0.4445 270)
			(size 0.1397 0.1397)
			(layers "B.Cu" "B.Mask" "B.Paste")
			(net "ROMA9")
			(options
				(clearance outline)
				(anchor circle)
			)
			(primitives
				(gr_poly
					(pts
						(arc
							(start -0.1778 0.2794)
							(mid -0.249642 0.249642)
							(end -0.2794 0.1778)
						)
						(arc
							(start -0.2794 -0.1778)
							(mid -0.249642 -0.249642)
							(end -0.1778 -0.2794)
						)
						(arc
							(start 0.1778 -0.2794)
							(mid 0.249642 -0.249642)
							(end 0.2794 -0.1778)
						)
						(arc
							(start 0.2794 0.1778)
							(mid 0.249642 0.249642)
							(end 0.1778 0.2794)
						)
					)
					(width 0)
					(fill yes)
				)
			)
		)
	)
	(footprint ""
		(layer "B.Cu")
		(at 239.1664 -51.9938 -90)
		(property "Reference" "C30"
			(at 0 0 90)
			(layer "B.SilkS")
			(hide yes)
			(effects
				(font
					(size 1.27 1.27)
				)
				(justify mirror)
			)
		)
		(property "Value" "SCD1U16V1KX-1-GP"
			(at 2.8321 -1.7399 270)
			(unlocked yes)
			(layer "B.Fab")
			(hide yes)
			(effects
				(font
					(size 1.016 1.016)
					(thickness 0.1524)
				)
				(justify mirror)
			)
		)
		(property "Device Type" "C0201H13"
			(at 2.8321 -3.2639 270)
			(unlocked yes)
			(layer "B.Fab")
			(hide yes)
			(effects
				(font
					(size 1.016 1.016)
					(thickness 0.1524)
				)
				(justify mirror)
			)
		)
		(duplicate_pad_numbers_are_jumpers no)
		(fp_rect
			(start 0.2794 0.6477)
			(end -0.2794 -0.6477)
			(stroke
				(width 0)
				(type default)
			)
			(fill no)
			(layer "B.CrtYd")
		)
		(fp_rect
			(start 0.2794 0.6477)
			(end -0.2794 -0.6477)
			(stroke
				(width 0)
				(type default)
			)
			(fill no)
			(layer "B.Fab")
		)
		(pad "1" smd custom
			(at 0 -0.2794 90)
			(size 0.0762 0.0762)
			(layers "B.Cu" "B.Mask" "B.Paste")
			(net "DUT_VDD")
			(options
				(clearance outline)
				(anchor circle)
			)
			(primitives
				(gr_poly
					(pts
						(arc
							(start 0.1524 0.127)
							(mid 0.137521 0.162921)
							(end 0.1016 0.1778)
						)
						(arc
							(start -0.1016 0.1778)
							(mid -0.137521 0.162921)
							(end -0.1524 0.127)
						)
						(arc
							(start -0.1524 -0.127)
							(mid -0.137521 -0.162921)
							(end -0.1016 -0.1778)
						)
						(arc
							(start 0.1016 -0.1778)
							(mid 0.137521 -0.162921)
							(end 0.1524 -0.127)
						)
					)
					(width 0)
					(fill yes)
				)
			)
		)
		(pad "2" smd custom
			(at 0 0.2794 90)
			(size 0.0762 0.0762)
			(layers "B.Cu" "B.Mask" "B.Paste")
			(net "GND")
			(options
				(clearance outline)
				(anchor circle)
			)
			(primitives
				(gr_poly
					(pts
						(arc
							(start 0.1524 0.127)
							(mid 0.137521 0.162921)
							(end 0.1016 0.1778)
						)
						(arc
							(start -0.1016 0.1778)
							(mid -0.137521 0.162921)
							(end -0.1524 0.127)
						)
						(arc
							(start -0.1524 -0.127)
							(mid -0.137521 -0.162921)
							(end -0.1016 -0.1778)
						)
						(arc
							(start 0.1016 -0.1778)
							(mid 0.137521 -0.162921)
							(end 0.1524 -0.127)
						)
					)
					(width 0)
					(fill yes)
				)
			)
		)
	)
	(footprint ""
		(layer "B.Cu")
		(at 73.578212 -192.641474)
		(property "Reference" "R3202"
			(at 0 0 0)
			(layer "B.SilkS")
			(hide yes)
			(effects
				(font
					(size 1.27 1.27)
				)
				(justify mirror)
			)
		)
		(property "Value" "0R2J-2-GP"
			(at -0.064008 -3.993896 0)
			(unlocked yes)
			(layer "B.Fab")
			(hide yes)
			(effects
				(font
					(size 1.016 1.016)
					(thickness 0.1524)
				)
				(justify mirror)
			)
		)
		(property "Device Type" "R402H16"
			(at -0.064008 -5.517896 0)
			(unlocked yes)
			(layer "B.Fab")
			(hide yes)
			(effects
				(font
					(size 1.016 1.016)
					(thickness 0.1524)
				)
				(justify mirror)
			)
		)
		(duplicate_pad_numbers_are_jumpers no)
		(fp_line
			(start -0.508 -0.9398)
			(end 0.508 -0.9398)
			(stroke
				(width 0.1524)
				(type default)
			)
			(layer "B.SilkS")
		)
		(fp_line
			(start 0.508 -0.9398)
			(end 0.508 0.9398)
			(stroke
				(width 0.1524)
				(type default)
			)
			(layer "B.SilkS")
		)
		(fp_rect
			(start 0.508 0.9398)
			(end -0.508 -0.9398)
			(stroke
				(width 0)
				(type default)
			)
			(fill no)
			(layer "B.CrtYd")
		)
		(fp_rect
			(start 0.508 0.9398)
			(end -0.508 -0.9398)
			(stroke
				(width 0)
				(type default)
			)
			(fill no)
			(layer "B.Fab")
		)
		(pad "1" smd custom
			(at 0 -0.4445 180)
			(size 0.1397 0.1397)
			(layers "B.Cu" "B.Mask" "B.Paste")
			(net "BMC_SSD_RST#0")
			(options
				(clearance outline)
				(anchor circle)
			)
			(primitives
				(gr_poly
					(pts
						(arc
							(start -0.1778 0.2794)
							(mid -0.249642 0.249642)
							(end -0.2794 0.1778)
						)
						(arc
							(start -0.2794 -0.1778)
							(mid -0.249642 -0.249642)
							(end -0.1778 -0.2794)
						)
						(arc
							(start 0.1778 -0.2794)
							(mid 0.249642 -0.249642)
							(end 0.2794 -0.1778)
						)
						(arc
							(start 0.2794 0.1778)
							(mid 0.249642 0.249642)
							(end 0.1778 0.2794)
						)
					)
					(width 0)
					(fill yes)
				)
			)
		)
		(pad "2" smd custom
			(at 0 0.4445 180)
			(size 0.1397 0.1397)
			(layers "B.Cu" "B.Mask" "B.Paste")
			(net "BMC_SSD_RST#0_A0")
			(options
				(clearance outline)
				(anchor circle)
			)
			(primitives
				(gr_poly
					(pts
						(arc
							(start -0.1778 0.2794)
							(mid -0.249642 0.249642)
							(end -0.2794 0.1778)
						)
						(arc
							(start -0.2794 -0.1778)
							(mid -0.249642 -0.249642)
							(end -0.1778 -0.2794)
						)
						(arc
							(start 0.1778 -0.2794)
							(mid 0.249642 -0.249642)
							(end 0.2794 -0.1778)
						)
						(arc
							(start 0.2794 0.1778)
							(mid 0.249642 0.249642)
							(end 0.1778 0.2794)
						)
					)
					(width 0)
					(fill yes)
				)
			)
		)
	)
	(footprint ""
		(layer "B.Cu")
		(at 246.126 -67.945 90)
		(property "Reference" "C507"
			(at 0 0 90)
			(layer "B.SilkS")
			(hide yes)
			(effects
				(font
					(size 1.27 1.27)
				)
				(justify mirror)
			)
		)
		(property "Value" "SC4D7U16V5KX-1-GP"
			(at 0.0762 -6.1214 90)
			(unlocked yes)
			(layer "B.Fab")
			(hide yes)
			(effects
				(font
					(size 1.016 1.016)
					(thickness 0.1524)
				)
				(justify mirror)
			)
		)
		(property "Device Type" "C805H56"
			(at 0.0762 -8.1534 90)
			(unlocked yes)
			(layer "B.Fab")
			(hide yes)
			(effects
				(font
					(size 1.016 1.016)
					(thickness 0.1524)
				)
				(justify mirror)
			)
		)
		(duplicate_pad_numbers_are_jumpers no)
		(fp_line
			(start -0.635 0)
			(end 0.635 0)
			(stroke
				(width 0.508)
				(type default)
			)
			(layer "B.SilkS")
		)
		(fp_rect
			(start 0.9652 1.778)
			(end -0.9652 -1.778)
			(stroke
				(width 0)
				(type default)
			)
			(fill no)
			(layer "B.CrtYd")
		)
		(fp_poly
			(pts
				(xy 0.9652 -1.778) (xy -0.9652 -1.778) (xy -0.9652 1.778) (xy 0.9652 1.778)
			)
			(stroke
				(width 0)
				(type default)
			)
			(fill no)
			(layer "B.Fab")
		)
		(pad "1" smd rect
			(at 0 -0.9652 270)
			(size 1.397 1.143)
			(layers "B.Cu" "B.Mask" "B.Paste")
			(net "DUT_AVD_TX")
		)
		(pad "2" smd rect
			(at 0 0.9652 270)
			(size 1.397 1.143)
			(layers "B.Cu" "B.Mask" "B.Paste")
			(net "GND")
		)
	)
	(footprint ""
		(layer "B.Cu")
		(at 70.033388 -189.603126)
		(property "Reference" "U75"
			(at 0 0 0)
			(layer "B.SilkS")
			(hide yes)
			(effects
				(font
					(size 1.27 1.27)
				)
				(justify mirror)
			)
		)
		(property "Value" "SN74LVC1G08DCKR-GP"
			(at 2.3368 -8.6868 0)
			(unlocked yes)
			(layer "B.Fab")
			(hide yes)
			(effects
				(font
					(size 1.016 1.016)
					(thickness 0.1524)
				)
				(justify mirror)
			)
		)
		(property "Device Type" "SC70-5H44"
			(at 2.3114 -10.414 0)
			(unlocked yes)
			(layer "B.Fab")
			(hide yes)
			(effects
				(font
					(size 1.016 1.016)
					(thickness 0.1524)
				)
				(justify mirror)
			)
		)
		(duplicate_pad_numbers_are_jumpers no)
		(fp_line
			(start -1.3843 -1.8034)
			(end -1.3843 -1.1176)
			(stroke
				(width 0.3302)
				(type default)
			)
			(layer "B.SilkS")
		)
		(fp_line
			(start -1.27 -1.7018)
			(end -1.27 1.7018)
			(stroke
				(width 0.1524)
				(type default)
			)
			(layer "B.SilkS")
		)
		(fp_line
			(start -1.27 1.7018)
			(end 1.27 1.7018)
			(stroke
				(width 0.1524)
				(type default)
			)
			(layer "B.SilkS")
		)
		(fp_line
			(start -0.6604 -1.8034)
			(end -1.3843 -1.8034)
			(stroke
				(width 0.3302)
				(type default)
			)
			(layer "B.SilkS")
		)
		(fp_line
			(start 1.27 -1.7018)
			(end -1.27 -1.7018)
			(stroke
				(width 0.1524)
				(type default)
			)
			(layer "B.SilkS")
		)
		(fp_line
			(start 1.27 1.7018)
			(end 1.27 -1.7018)
			(stroke
				(width 0.1524)
				(type default)
			)
			(layer "B.SilkS")
		)
		(fp_rect
			(start 1.524 1.9558)
			(end -1.524 -1.9558)
			(stroke
				(width 0)
				(type default)
			)
			(fill no)
			(layer "B.CrtYd")
		)
		(fp_poly
			(pts
				(xy 1.524 -1.9558) (xy -1.524 -1.9558) (xy -1.524 1.9558) (xy 1.524 1.9558)
			)
			(stroke
				(width 0)
				(type default)
			)
			(fill no)
			(layer "B.Fab")
		)
		(pad "1" smd rect
			(at -0.65024 -0.8255 180)
			(size 0.4064 1.2192)
			(layers "B.Cu" "B.Mask" "B.Paste")
			(net "BMC_SSD_RST#0_A11")
		)
		(pad "2" smd rect
			(at 0 -0.8255 180)
			(size 0.4064 1.2192)
			(layers "B.Cu" "B.Mask" "B.Paste")
			(net "SSD_PERST#0_B11")
		)
		(pad "3" smd rect
			(at 0.65024 -0.8255 180)
			(size 0.4064 1.2192)
			(layers "B.Cu" "B.Mask" "B.Paste")
			(net "GND")
		)
		(pad "4" smd rect
			(at 0.65024 0.8255 180)
			(size 0.4064 1.2192)
			(layers "B.Cu" "B.Mask" "B.Paste")
			(net "SSD_PERST_Y11")
		)
		(pad "5" smd rect
			(at -0.65024 0.8255 180)
			(size 0.4064 1.2192)
			(layers "B.Cu" "B.Mask" "B.Paste")
			(net "P3V3_STBY")
		)
	)
	(footprint ""
		(layer "B.Cu")
		(at 217.805 -198.12)
		(property "Reference" "R145"
			(at 0 0 0)
			(layer "B.SilkS")
			(hide yes)
			(effects
				(font
					(size 1.27 1.27)
				)
				(justify mirror)
			)
		)
		(property "Value" "4K7R2F-GP"
			(at -0.064008 -3.993896 0)
			(unlocked yes)
			(layer "B.Fab")
			(hide yes)
			(effects
				(font
					(size 1.016 1.016)
					(thickness 0.1524)
				)
				(justify mirror)
			)
		)
		(property "Device Type" "R402H16"
			(at -0.064008 -5.517896 0)
			(unlocked yes)
			(layer "B.Fab")
			(hide yes)
			(effects
				(font
					(size 1.016 1.016)
					(thickness 0.1524)
				)
				(justify mirror)
			)
		)
		(duplicate_pad_numbers_are_jumpers no)
		(fp_line
			(start -0.508 -0.9398)
			(end 0.508 -0.9398)
			(stroke
				(width 0.1524)
				(type default)
			)
			(layer "B.SilkS")
		)
		(fp_line
			(start 0.508 -0.9398)
			(end 0.508 0.9398)
			(stroke
				(width 0.1524)
				(type default)
			)
			(layer "B.SilkS")
		)
		(fp_rect
			(start 0.508 0.9398)
			(end -0.508 -0.9398)
			(stroke
				(width 0)
				(type default)
			)
			(fill no)
			(layer "B.CrtYd")
		)
		(fp_rect
			(start 0.508 0.9398)
			(end -0.508 -0.9398)
			(stroke
				(width 0)
				(type default)
			)
			(fill no)
			(layer "B.Fab")
		)
		(pad "1" smd custom
			(at 0 -0.4445 180)
			(size 0.1397 0.1397)
			(layers "B.Cu" "B.Mask" "B.Paste")
			(net "BMC_SSD_RST#0_A3")
			(options
				(clearance outline)
				(anchor circle)
			)
			(primitives
				(gr_poly
					(pts
						(arc
							(start -0.1778 0.2794)
							(mid -0.249642 0.249642)
							(end -0.2794 0.1778)
						)
						(arc
							(start -0.2794 -0.1778)
							(mid -0.249642 -0.249642)
							(end -0.1778 -0.2794)
						)
						(arc
							(start 0.1778 -0.2794)
							(mid 0.249642 -0.249642)
							(end 0.2794 -0.1778)
						)
						(arc
							(start 0.2794 0.1778)
							(mid 0.249642 0.249642)
							(end 0.1778 0.2794)
						)
					)
					(width 0)
					(fill yes)
				)
			)
		)
		(pad "2" smd custom
			(at 0 0.4445 180)
			(size 0.1397 0.1397)
			(layers "B.Cu" "B.Mask" "B.Paste")
			(net "P3V3_STBY")
			(options
				(clearance outline)
				(anchor circle)
			)
			(primitives
				(gr_poly
					(pts
						(arc
							(start -0.1778 0.2794)
							(mid -0.249642 0.249642)
							(end -0.2794 0.1778)
						)
						(arc
							(start -0.2794 -0.1778)
							(mid -0.249642 -0.249642)
							(end -0.1778 -0.2794)
						)
						(arc
							(start 0.1778 -0.2794)
							(mid 0.249642 -0.249642)
							(end 0.2794 -0.1778)
						)
						(arc
							(start 0.2794 0.1778)
							(mid 0.249642 0.249642)
							(end 0.1778 0.2794)
						)
					)
					(width 0)
					(fill yes)
				)
			)
		)
	)
	(footprint ""
		(layer "B.Cu")
		(at 45.72 -131.445 90)
		(property "Reference" "R337"
			(at 0 0 90)
			(layer "B.SilkS")
			(hide yes)
			(effects
				(font
					(size 1.27 1.27)
				)
				(justify mirror)
			)
		)
		(property "Value" "49K9R2F-L-GP"
			(at -0.064008 -3.993896 90)
			(unlocked yes)
			(layer "B.Fab")
			(hide yes)
			(effects
				(font
					(size 1.016 1.016)
					(thickness 0.1524)
				)
				(justify mirror)
			)
		)
		(property "Device Type" "R402H16"
			(at -0.064008 -5.517896 90)
			(unlocked yes)
			(layer "B.Fab")
			(hide yes)
			(effects
				(font
					(size 1.016 1.016)
					(thickness 0.1524)
				)
				(justify mirror)
			)
		)
		(duplicate_pad_numbers_are_jumpers no)
		(fp_line
			(start 0.508 -0.9398)
			(end 0.508 0.9398)
			(stroke
				(width 0.1524)
				(type default)
			)
			(layer "B.SilkS")
		)
		(fp_line
			(start -0.508 -0.9398)
			(end 0.508 -0.9398)
			(stroke
				(width 0.1524)
				(type default)
			)
			(layer "B.SilkS")
		)
		(fp_rect
			(start 0.508 0.9398)
			(end -0.508 -0.9398)
			(stroke
				(width 0)
				(type default)
			)
			(fill no)
			(layer "B.CrtYd")
		)
		(fp_rect
			(start 0.508 0.9398)
			(end -0.508 -0.9398)
			(stroke
				(width 0)
				(type default)
			)
			(fill no)
			(layer "B.Fab")
		)
		(pad "1" smd custom
			(at 0 -0.4445 270)
			(size 0.1397 0.1397)
			(layers "B.Cu" "B.Mask" "B.Paste")
			(net "GND")
			(options
				(clearance outline)
				(anchor circle)
			)
			(primitives
				(gr_poly
					(pts
						(arc
							(start -0.1778 0.2794)
							(mid -0.249642 0.249642)
							(end -0.2794 0.1778)
						)
						(arc
							(start -0.2794 -0.1778)
							(mid -0.249642 -0.249642)
							(end -0.1778 -0.2794)
						)
						(arc
							(start 0.1778 -0.2794)
							(mid 0.249642 -0.249642)
							(end 0.2794 -0.1778)
						)
						(arc
							(start 0.2794 0.1778)
							(mid 0.249642 0.249642)
							(end 0.1778 0.2794)
						)
					)
					(width 0)
					(fill yes)
				)
			)
		)
		(pad "2" smd custom
			(at 0 0.4445 270)
			(size 0.1397 0.1397)
			(layers "B.Cu" "B.Mask" "B.Paste")
			(net "ADCVREXT")
			(options
				(clearance outline)
				(anchor circle)
			)
			(primitives
				(gr_poly
					(pts
						(arc
							(start -0.1778 0.2794)
							(mid -0.249642 0.249642)
							(end -0.2794 0.1778)
						)
						(arc
							(start -0.2794 -0.1778)
							(mid -0.249642 -0.249642)
							(end -0.1778 -0.2794)
						)
						(arc
							(start 0.1778 -0.2794)
							(mid 0.249642 -0.249642)
							(end 0.2794 -0.1778)
						)
						(arc
							(start 0.2794 0.1778)
							(mid 0.249642 0.249642)
							(end 0.1778 0.2794)
						)
					)
					(width 0)
					(fill yes)
				)
			)
		)
	)
	(footprint ""
		(layer "B.Cu")
		(at 244.599968 -39.99992 -90)
		(property "Reference" "TP238"
			(at 0 0 90)
			(layer "B.SilkS")
			(hide yes)
			(effects
				(font
					(size 1.27 1.27)
				)
				(justify mirror)
			)
		)
		(property "Value" "TPAD28-2-GP"
			(at 0.0127 -1.6637 270)
			(unlocked yes)
			(layer "B.Fab")
			(hide yes)
			(effects
				(font
					(size 1.016 1.016)
					(thickness 0.1524)
				)
				(justify mirror)
			)
		)
		(property "Device Type" "TPAD28"
			(at 0.0127 -3.1877 270)
			(unlocked yes)
			(layer "B.Fab")
			(hide yes)
			(effects
				(font
					(size 1.016 1.016)
					(thickness 0.1524)
				)
				(justify mirror)
			)
		)
		(duplicate_pad_numbers_are_jumpers no)
		(fp_poly
			(pts
				(arc
					(start 0 -0.3556)
					(mid 0 0.3556)
					(end 0 -0.3556)
				)
			)
			(stroke
				(width 0)
				(type default)
			)
			(fill no)
			(layer "B.CrtYd")
		)
		(fp_poly
			(pts
				(arc
					(start 0 -0.6096)
					(mid 0 0.6096)
					(end 0 -0.6096)
				)
			)
			(stroke
				(width 0)
				(type default)
			)
			(fill no)
			(layer "B.Fab")
		)
		(pad "1" smd circle
			(at 0 0 90)
			(size 0.7112 0.7112)
			(layers "B.Cu" "B.Mask" "B.Paste")
			(net "RS232_UCTSB0")
		)
	)
)
